# T6G (Grand Teton) — schematic netlist excerpt (pin names and nets, part order shuffled) for the footprints in the layout excerpt that follows; sources: Cadence DE-HDL packaged netlist, KiCad conversion of 04192023_DAF0TMB3IC0_F0TG_MB_C_brd_V02_OCP.brd

J19  SCONN288_DDR506112002KQ  IO  pkg DDR288S_1-1VXC  page 89
  VIN_BULK0  = P12V_MEM_CPU0
  RFU0  = NC
  VIN_MGMT  = P3V3_AUX
  HSCL  = I3C_SPD_DDRD_CPU0_SCL
  HSDA  = I3C_SPD_DDRD_CPU0_SDA
  VSS0  = GND
  DQ0_A  = M_D_CPU0_SA_DQ<0>
  VSS1  = GND
  DQ1_A  = M_D_CPU0_SA_DQ<1>
  VSS2  = GND
  DQS0_A_T  = M_D_CPU0_SA_DQS_DP<0>
  DQS0_A_C  = M_D_CPU0_SA_DQS_DN<0>
  VSS3  = GND
  DQ4_A  = M_D_CPU0_SA_DQ<4>
  VSS4  = GND
  DQ5_A  = M_D_CPU0_SA_DQ<5>
  VSS5  = GND
  DQ8_A  = M_D_CPU0_SA_DQ<8>
  VSS6  = GND
  DQ9_A  = M_D_CPU0_SA_DQ<9>
  VSS7  = GND
  DQS1_A_T  = M_D_CPU0_SA_DQS_DP<1>
  DQS1_A_C  = M_D_CPU0_SA_DQS_DN<1>
  VSS8  = GND
  DQ12_A  = M_D_CPU0_SA_DQ<12>
  VSS9  = GND
  DQ13_A  = M_D_CPU0_SA_DQ<13>
  VSS10  = GND
  DQ16_A  = M_D_CPU0_SA_DQ<16>
  VSS11  = GND
  DQ17_A  = M_D_CPU0_SA_DQ<17>
  VSS12  = GND
  DQS2_A_T  = M_D_CPU0_SA_DQS_DP<2>
  DQS2_A_C  = M_D_CPU0_SA_DQS_DN<2>
  VSS13  = GND
  DQ20_A  = M_D_CPU0_SA_DQ<20>
  VSS14  = GND
  DQ21_A  = M_D_CPU0_SA_DQ<21>
  VSS15  = GND
  DQ24_A  = M_D_CPU0_SA_DQ<24>
  VSS16  = GND
  DQ25_A  = M_D_CPU0_SA_DQ<25>
  VSS17  = GND
  DQS3_A_T  = M_D_CPU0_SA_DQS_DP<3>
  DQS3_A_C  = M_D_CPU0_SA_DQS_DN<3>
  VSS18  = GND
  DQ28_A  = M_D_CPU0_SA_DQ<28>
  VSS19  = GND
  DQ29_A  = M_D_CPU0_SA_DQ<29>
  VSS20  = GND
  CB0_A  = M_D_CPU0_SA_CB<0>
  VSS21  = GND
  CB1_A  = M_D_CPU0_SA_CB<1>
  VSS22  = GND
  DQS4_A_T  = M_D_CPU0_SA_DQS_DP<4>
  DQS4_A_C  = M_D_CPU0_SA_DQS_DN<4>
  VSS23  = GND
  CB4_A  = M_D_CPU0_SA_CB<4>
  VSS24  = GND
  CB5_A  = M_D_CPU0_SA_CB<5>
  VSS25  = GND
  ALERT_N  = M_D_CPU0_ALERT_N
  VSS26  = GND
  CS0_A_N  = M_D_CPU0_SA_CS_N<0>
  VSS27  = GND
  CA0_A  = M_D_CPU0_SA_CA<0>
  VSS28  = GND
  CA2_A  = M_D_CPU0_SA_CA<2>
  VSS29  = GND
  CA4_A  = M_D_CPU0_SA_CA<4>
  VSS30  = GND
  CA6_A  = M_D_CPU0_SA_CA<6>
  VSS31  = GND
  PAR_A  = M_D_CPU0_SA_PAR
  VSS32  = GND
  CA0_B  = M_D_CPU0_SB_CA<0>
  VSS33  = GND
  CA2_B  = M_D_CPU0_SB_CA<2>
  VSS34  = GND
  CA4_B  = M_D_CPU0_SB_CA<4>
  VSS35  = GND
  CA6_B  = M_D_CPU0_SB_CA<6>
  VSS36  = GND
  CS0_B_N  = M_D_CPU0_SB_CS_N<0>
  VSS37  = GND
  \lbd||rsp_a_n\  = M_D_CPU0_SA_RSP<0>
  \lbs||rsp_b_n\  = M_D_CPU0_SB_RSP<0>
  VSS38  = GND
  CB4_B  = M_D_CPU0_SB_CB<4>
  VSS39  = GND
  CB5_B  = M_D_CPU0_SB_CB<5>
  VSS40  = GND
  \dqs9_b_t||tdqs9_b_t||dbi4_b_n\  = M_D_CPU0_SB_DQS_DP<9>
  \dqs9_b_c||tdqs9_b_c\  = M_D_CPU0_SB_DQS_DN<9>
  VSS41  = GND
  CB0_B  = M_D_CPU0_SB_CB<0>
  VSS42  = GND
  CB1_B  = M_D_CPU0_SB_CB<1>
  VSS43  = GND
  DQ0_B  = M_D_CPU0_SB_DQ<0>
  VSS44  = GND
  DQ1_B  = M_D_CPU0_SB_DQ<1>
  VSS45  = GND
  DQS0_B_T  = M_D_CPU0_SB_DQS_DP<0>
  DQS0_B_C  = M_D_CPU0_SB_DQS_DN<0>
  VSS46  = GND
  DQ4_B  = M_D_CPU0_SB_DQ<4>
  VSS47  = GND
  DQ5_B  = M_D_CPU0_SB_DQ<5>
  VSS48  = GND
  DQ8_B  = M_D_CPU0_SB_DQ<8>
  VSS49  = GND
  DQ9_B  = M_D_CPU0_SB_DQ<9>
  VSS50  = GND
  DQS1_B_T  = M_D_CPU0_SB_DQS_DP<1>
  DQS1_B_C  = M_D_CPU0_SB_DQS_DN<1>
  VSS51  = GND
  DQ12_B  = M_D_CPU0_SB_DQ<12>
  VSS52  = GND
  DQ13_B  = M_D_CPU0_SB_DQ<13>
  VSS53  = GND
  DQ16_B  = M_D_CPU0_SB_DQ<16>
  VSS54  = GND
  DQ17_B  = M_D_CPU0_SB_DQ<17>
  VSS55  = GND
  DQS2_B_T  = M_D_CPU0_SB_DQS_DP<2>
  DQS2_B_C  = M_D_CPU0_SB_DQS_DN<2>
  VSS56  = GND
  DQ20_B  = M_D_CPU0_SB_DQ<20>
  VSS57  = GND
  DQ21_B  = M_D_CPU0_SB_DQ<21>
  VSS58  = GND
  DQ24_B  = M_D_CPU0_SB_DQ<24>
  VSS59  = GND
  DQ25_B  = M_D_CPU0_SB_DQ<25>
  VSS60  = GND
  DQS3_B_T  = M_D_CPU0_SB_DQS_DP<3>
  DQS3_B_C  = M_D_CPU0_SB_DQS_DN<3>
  VSS61  = GND
  DQ28_B  = M_D_CPU0_SB_DQ<28>
  VSS62  = GND
  DQ29_B  = M_D_CPU0_SB_DQ<29>
  VSS63  = GND
  RFU1  = NC
  VIN_BULK1  = P12V_MEM_CPU0
  VIN_BULK2  = P12V_MEM_CPU0
  \pwr_good||fail_n\  = PWRGD_CHD_CPU0_DIMM
  HAS  = PD_CHD_CPU0_DIMM_SAA
  RFU2  = NC
  RFU3  = NC
  VSS64  = GND
  DQ2_A  = M_D_CPU0_SA_DQ<2>
  VSS65  = GND
  DQ3_A  = M_D_CPU0_SA_DQ<3>
  VSS66  = GND
  \dqs5_a_c||tdqs5_a_c||dqs5_a_t||tdqs5_a_t\  = M_D_CPU0_SA_DQS_DN<5>
  \dqs5_a_t||tdqs5_a_t\  = M_D_CPU0_SA_DQS_DP<5>
  VSS67  = GND
  DQ6_A  = M_D_CPU0_SA_DQ<6>
  VSS68  = GND
  DQ7_A  = M_D_CPU0_SA_DQ<7>
  VSS69  = GND
  DQ10_A  = M_D_CPU0_SA_DQ<10>
  VSS70  = GND
  DQ11_A  = M_D_CPU0_SA_DQ<11>
  VSS71  = GND
  \dqs6_a_c||tdqs6_a_c||dqs6_a_t||tdqs6_a_t\  = M_D_CPU0_SA_DQS_DN<6>
  \dqs6_a_t||tdqs6_a_t\  = M_D_CPU0_SA_DQS_DP<6>
  VSS72  = GND
  DQ14_A  = M_D_CPU0_SA_DQ<14>
  VSS73  = GND
  DQ15_A  = M_D_CPU0_SA_DQ<15>
  VSS74  = GND
  DQ18_A  = M_D_CPU0_SA_DQ<18>
  VSS75  = GND
  DQ19_A  = M_D_CPU0_SA_DQ<19>
  VSS76  = GND
  \dqs7_a_c||tdqs7_a_c\  = M_D_CPU0_SA_DQS_DN<7>
  \dqs7_a_t||tdqs7_a_t\  = M_D_CPU0_SA_DQS_DP<7>
  VSS77  = GND
  DQ22_A  = M_D_CPU0_SA_DQ<22>
  VSS78  = GND
  DQ23_A  = M_D_CPU0_SA_DQ<23>
  VSS79  = GND
  DQ26_A  = M_D_CPU0_SA_DQ<26>
  VSS80  = GND
  DQ27_A  = M_D_CPU0_SA_DQ<27>
  VSS81  = GND
  \dqs8_a_c||tdqs8_a_c\  = M_D_CPU0_SA_DQS_DN<8>
  \dqs8_a_t||tdqs8_a_t\  = M_D_CPU0_SA_DQS_DP<8>
  VSS82  = GND
  DQ30_A  = M_D_CPU0_SA_DQ<30>
  VSS83  = GND
  DQ31_A  = M_D_CPU0_SA_DQ<31>
  VSS84  = GND
  CB2_A  = M_D_CPU0_SA_CB<2>
  VSS85  = GND
  CB3_A  = M_D_CPU0_SA_CB<3>
  VSS86  = GND
  \dqs9_a_c||tdqs9_a_c\  = M_D_CPU0_SA_DQS_DN<9>
  \dqs9_a_t||tdqs9_a_t\  = M_D_CPU0_SA_DQS_DP<9>
  VSS87  = GND
  CB6_A  = M_D_CPU0_SA_CB<6>
  VSS88  = GND
  CB7_A  = M_D_CPU0_SA_CB<7>
  VSS89  = GND
  RESET_N  = M_D_CPU0_RESET_N
  VSS90  = GND
  CS1_A_N  = M_D_CPU0_SA_CS_N<1>
  VSS91  = GND
  CA1_A  = M_D_CPU0_SA_CA<1>
  VSS92  = GND
  CA3_A  = M_D_CPU0_SA_CA<3>
  VSS93  = GND
  CA5_A  = M_D_CPU0_SA_CA<5>
  VSS94  = GND
  CK_T  = M_D_CPU0_CLK_DP<0>
  CK_C  = M_D_CPU0_CLK_DN<0>
  VSS95  = GND
  RFU4  = NC
  CA1_B  = M_D_CPU0_SB_CA<1>
  VSS96  = GND
  CA3_B  = M_D_CPU0_SB_CA<3>
  VSS97  = GND
  CA5_B  = M_D_CPU0_SB_CA<5>
  VSS98  = GND
  PAR_B  = M_D_CPU0_SB_PAR
  VSS99  = GND
  CS1_B_N  = M_D_CPU0_SB_CS_N<1>
  VSS100  = GND
  RFU5  = NC
  RFU6  = NC
  VSS101  = GND
  CB6_B  = M_D_CPU0_SB_CB<6>
  VSS102  = GND
  CB7_B  = M_D_CPU0_SB_CB<7>
  VSS103  = GND
  DQS4_B_C  = M_D_CPU0_SB_DQS_DN<4>
  DQS4_B_T  = M_D_CPU0_SB_DQS_DP<4>
  VSS104  = GND
  CB2_B  = M_D_CPU0_SB_CB<2>
  VSS105  = GND
  CB3_B  = M_D_CPU0_SB_CB<3>
  VSS106  = GND
  DQ2_B  = M_D_CPU0_SB_DQ<2>
  VSS107  = GND
  DQ3_B  = M_D_CPU0_SB_DQ<3>
  VSS108  = GND
  \dqs5_b_c||tdqs5_b_c\  = M_D_CPU0_SB_DQS_DN<5>
  \dqs5_b_t||tdqs5_b_t\  = M_D_CPU0_SB_DQS_DP<5>
  VSS109  = GND
  DQ6_B  = M_D_CPU0_SB_DQ<6>
  VSS110  = GND
  DQ7_B  = M_D_CPU0_SB_DQ<7>
  VSS111  = GND
  DQ10_B  = M_D_CPU0_SB_DQ<10>
  VSS112  = GND
  DQ11_B  = M_D_CPU0_SB_DQ<11>
  VSS113  = GND
  \dqs6_b_c||tdqs6_b_c\  = M_D_CPU0_SB_DQS_DN<6>
  \dqs6_b_t||tdqs6_b_t\  = M_D_CPU0_SB_DQS_DP<6>
  VSS114  = GND
  DQ14_B  = M_D_CPU0_SB_DQ<14>
  VSS115  = GND
  DQ15_B  = M_D_CPU0_SB_DQ<15>
  VSS116  = GND
  DQ18_B  = M_D_CPU0_SB_DQ<18>
  VSS117  = GND
  DQ19_B  = M_D_CPU0_SB_DQ<19>
  VSS118  = GND
  \dqs7_b_c||tdqs7_b_c\  = M_D_CPU0_SB_DQS_DN<7>
  \dqs7_b_t||tdqs7_b_t\  = M_D_CPU0_SB_DQS_DP<7>
  VSS119  = GND
  DQ22_B  = M_D_CPU0_SB_DQ<22>
  VSS120  = GND
  DQ23_B  = M_D_CPU0_SB_DQ<23>
  VSS121  = GND
  DQ26_B  = M_D_CPU0_SB_DQ<26>
  VSS122  = GND
  DQ27_B  = M_D_CPU0_SB_DQ<27>
  VSS123  = GND
  \dqs8_b_c||tdqs8_b_c\  = M_D_CPU0_SB_DQS_DN<8>
  \dqs8_b_t||tdqs8_b_t\  = M_D_CPU0_SB_DQS_DP<8>
  VSS124  = GND
  DQ30_B  = M_D_CPU0_SB_DQ<30>
  VSS125  = GND
  DQ31_B  = M_D_CPU0_SB_DQ<31>
  VSS126  = GND
  G1  = GND
  G2  = GND
  G3  = GND

(kicad_pcb
	(version 20260206)
	(generator "pcbnew")
	(generator_version "10.0")
	(general
		(thickness 1.6)
		(legacy_teardrops no)
	)
	(paper "A4")
	(title_block
		(title "04192023_DAF0TMB3IC0_F0TG_MB_C_brd_V02_OCP.brd")
		(comment 1 "Grand Teton / footprint 2350 of 8354 (J19), pads 47-92 of 291")
	)
	(layers
		(0 "F.Cu" signal "TOP")
		(4 "In1.Cu" signal "GND")
		(6 "In2.Cu" signal "IN1")
		(8 "In3.Cu" signal "GND1")
		(10 "In4.Cu" signal "IN2")
		(12 "In5.Cu" signal "GND2")
		(14 "In6.Cu" signal "IN3")
		(16 "In7.Cu" signal "GND3")
		(18 "In8.Cu" signal "VCC")
		(20 "In9.Cu" signal "VCC1")
		(22 "In10.Cu" signal "GND4")
		(24 "In11.Cu" signal "IN4")
		(26 "In12.Cu" signal "GND5")
		(28 "In13.Cu" signal "IN5")
		(30 "In14.Cu" signal "GND6")
		(32 "In15.Cu" signal "IN6")
		(34 "In16.Cu" signal "GND7")
		(2 "B.Cu" signal "BOTTOM")
		(9 "F.Adhes" user "F.Adhesive")
		(11 "B.Adhes" user "B.Adhesive")
		(13 "F.Paste" user "Package Geometry/Pastemask Top")
		(15 "B.Paste" user "Package Geometry/Pastemask Bottom")
		(5 "F.SilkS" user "Ref Des/Silkscreen Top")
		(7 "B.SilkS" user "Ref Des/Silkscreen Bottom")
		(1 "F.Mask" user "Board Geometry/Soldermask Top")
		(3 "B.Mask" user "Board Geometry/Soldermask Bottom")
		(17 "Dwgs.User" user "User.Drawings")
		(19 "Cmts.User" user "User.Comments")
		(21 "Eco1.User" user "User.Eco1")
		(23 "Eco2.User" user "User.Eco2")
		(25 "Edge.Cuts" user "Board Geometry/Outline")
		(27 "Margin" user)
		(31 "F.CrtYd" user "Package Geometry/Place Bound Top")
		(29 "B.CrtYd" user "Package Geometry/Place Bound Bottom")
		(35 "F.Fab" user "Ref Des/Assembly Top")
		(33 "B.Fab" user "Ref Des/Assembly Bottom")
	)
	(footprint ""
		(layer "F.Cu")
		(at 282.685998 -255.560068 180)
		(property "Reference" "J19"
			(at -2.2098 -81.984088 0)
			(unlocked yes)
			(layer "F.SilkS")
			(effects
				(font
					(size 0.7874 0.5842)
					(thickness 0.1524)
				)
			)
		)
		(property "Value" ""
			(at 0 0 180)
			(layer "F.Fab")
			(effects
				(font
					(size 1.27 1.27)
				)
			)
		)
		(duplicate_pad_numbers_are_jumpers no)
		(pad "47" smd rect
			(at -2.050034 -24.224996 90)
			(size 0.519938 1.4986)
			(layers "F.Cu" "F.Mask" "F.Paste")
			(net "M_D_CPU0_SA_DQ<28>")
		)
		(pad "48" smd rect
			(at -2.050034 -23.375112 90)
			(size 0.519938 1.4986)
			(layers "F.Cu" "F.Mask" "F.Paste")
			(net "GND")
		)
		(pad "49" smd rect
			(at -2.050034 -22.524974 90)
			(size 0.519938 1.4986)
			(layers "F.Cu" "F.Mask" "F.Paste")
			(net "M_D_CPU0_SA_DQ<29>")
		)
		(pad "50" smd rect
			(at -2.050034 -21.67509 90)
			(size 0.519938 1.4986)
			(layers "F.Cu" "F.Mask" "F.Paste")
			(net "GND")
		)
		(pad "51" smd rect
			(at -2.050034 -20.824952 90)
			(size 0.519938 1.4986)
			(layers "F.Cu" "F.Mask" "F.Paste")
			(net "M_D_CPU0_SA_CB<0>")
		)
		(pad "52" smd rect
			(at -2.050034 -19.975068 90)
			(size 0.519938 1.4986)
			(layers "F.Cu" "F.Mask" "F.Paste")
			(net "GND")
		)
		(pad "53" smd rect
			(at -2.050034 -19.12493 90)
			(size 0.519938 1.4986)
			(layers "F.Cu" "F.Mask" "F.Paste")
			(net "M_D_CPU0_SA_CB<1>")
		)
		(pad "54" smd rect
			(at -2.050034 -18.275046 90)
			(size 0.519938 1.4986)
			(layers "F.Cu" "F.Mask" "F.Paste")
			(net "GND")
		)
		(pad "55" smd rect
			(at -2.050034 -17.424908 90)
			(size 0.519938 1.4986)
			(layers "F.Cu" "F.Mask" "F.Paste")
			(net "M_D_CPU0_SA_DQS_DP<4>")
		)
		(pad "56" smd rect
			(at -2.050034 -16.575024 90)
			(size 0.519938 1.4986)
			(layers "F.Cu" "F.Mask" "F.Paste")
			(net "M_D_CPU0_SA_DQS_DN<4>")
		)
		(pad "57" smd rect
			(at -2.050034 -15.724886 90)
			(size 0.519938 1.4986)
			(layers "F.Cu" "F.Mask" "F.Paste")
			(net "GND")
		)
		(pad "58" smd rect
			(at -2.050034 -14.875002 90)
			(size 0.519938 1.4986)
			(layers "F.Cu" "F.Mask" "F.Paste")
			(net "M_D_CPU0_SA_CB<4>")
		)
		(pad "59" smd rect
			(at -2.050034 -14.025118 90)
			(size 0.519938 1.4986)
			(layers "F.Cu" "F.Mask" "F.Paste")
			(net "GND")
		)
		(pad "60" smd rect
			(at -2.050034 -13.17498 90)
			(size 0.519938 1.4986)
			(layers "F.Cu" "F.Mask" "F.Paste")
			(net "M_D_CPU0_SA_CB<5>")
		)
		(pad "61" smd rect
			(at -2.050034 -12.325096 90)
			(size 0.519938 1.4986)
			(layers "F.Cu" "F.Mask" "F.Paste")
			(net "GND")
		)
		(pad "62" smd rect
			(at -2.050034 -11.474958 90)
			(size 0.519938 1.4986)
			(layers "F.Cu" "F.Mask" "F.Paste")
			(net "M_D_CPU0_ALERT_N")
		)
		(pad "63" smd rect
			(at -2.050034 -10.625074 90)
			(size 0.519938 1.4986)
			(layers "F.Cu" "F.Mask" "F.Paste")
			(net "GND")
		)
		(pad "64" smd rect
			(at -2.050034 -9.774936 90)
			(size 0.519938 1.4986)
			(layers "F.Cu" "F.Mask" "F.Paste")
			(net "M_D_CPU0_SA_CS_N<0>")
		)
		(pad "65" smd rect
			(at -2.050034 -8.925052 90)
			(size 0.519938 1.4986)
			(layers "F.Cu" "F.Mask" "F.Paste")
			(net "GND")
		)
		(pad "66" smd rect
			(at -2.050034 -8.074914 90)
			(size 0.519938 1.4986)
			(layers "F.Cu" "F.Mask" "F.Paste")
			(net "M_D_CPU0_SA_CA<0>")
		)
		(pad "67" smd rect
			(at -2.050034 -7.22503 90)
			(size 0.519938 1.4986)
			(layers "F.Cu" "F.Mask" "F.Paste")
			(net "GND")
		)
		(pad "68" smd rect
			(at -2.050034 -6.374892 90)
			(size 0.519938 1.4986)
			(layers "F.Cu" "F.Mask" "F.Paste")
			(net "M_D_CPU0_SA_CA<2>")
		)
		(pad "69" smd rect
			(at -2.050034 -5.525008 90)
			(size 0.519938 1.4986)
			(layers "F.Cu" "F.Mask" "F.Paste")
			(net "GND")
		)
		(pad "70" smd rect
			(at -2.050034 -4.675124 90)
			(size 0.519938 1.4986)
			(layers "F.Cu" "F.Mask" "F.Paste")
			(net "M_D_CPU0_SA_CA<4>")
		)
		(pad "71" smd rect
			(at -2.050034 -3.824986 90)
			(size 0.519938 1.4986)
			(layers "F.Cu" "F.Mask" "F.Paste")
			(net "GND")
		)
		(pad "72" smd rect
			(at -2.050034 -2.975102 90)
			(size 0.519938 1.4986)
			(layers "F.Cu" "F.Mask" "F.Paste")
			(net "M_D_CPU0_SA_CA<6>")
		)
		(pad "73" smd rect
			(at -2.050034 -2.124964 90)
			(size 0.519938 1.4986)
			(layers "F.Cu" "F.Mask" "F.Paste")
			(net "GND")
		)
		(pad "74" smd rect
			(at -2.050034 -1.27508 90)
			(size 0.519938 1.4986)
			(layers "F.Cu" "F.Mask" "F.Paste")
			(net "M_D_CPU0_SA_PAR")
		)
		(pad "75" smd rect
			(at -2.050034 -0.424942 90)
			(size 0.519938 1.4986)
			(layers "F.Cu" "F.Mask" "F.Paste")
			(net "GND")
		)
		(pad "76" smd rect
			(at -2.050034 5.525008 90)
			(size 0.519938 1.4986)
			(layers "F.Cu" "F.Mask" "F.Paste")
			(net "M_D_CPU0_SB_CA<0>")
		)
		(pad "77" smd rect
			(at -2.050034 6.374892 90)
			(size 0.519938 1.4986)
			(layers "F.Cu" "F.Mask" "F.Paste")
			(net "GND")
		)
		(pad "78" smd rect
			(at -2.050034 7.22503 90)
			(size 0.519938 1.4986)
			(layers "F.Cu" "F.Mask" "F.Paste")
			(net "M_D_CPU0_SB_CA<2>")
		)
		(pad "79" smd rect
			(at -2.050034 8.074914 90)
			(size 0.519938 1.4986)
			(layers "F.Cu" "F.Mask" "F.Paste")
			(net "GND")
		)
		(pad "80" smd rect
			(at -2.050034 8.925052 90)
			(size 0.519938 1.4986)
			(layers "F.Cu" "F.Mask" "F.Paste")
			(net "M_D_CPU0_SB_CA<4>")
		)
		(pad "81" smd rect
			(at -2.050034 9.774936 90)
			(size 0.519938 1.4986)
			(layers "F.Cu" "F.Mask" "F.Paste")
			(net "GND")
		)
		(pad "82" smd rect
			(at -2.050034 10.625074 90)
			(size 0.519938 1.4986)
			(layers "F.Cu" "F.Mask" "F.Paste")
			(net "M_D_CPU0_SB_CA<6>")
		)
		(pad "83" smd rect
			(at -2.050034 11.474958 90)
			(size 0.519938 1.4986)
			(layers "F.Cu" "F.Mask" "F.Paste")
			(net "GND")
		)
		(pad "84" smd rect
			(at -2.050034 12.325096 90)
			(size 0.519938 1.4986)
			(layers "F.Cu" "F.Mask" "F.Paste")
			(net "M_D_CPU0_SB_CS_N<0>")
		)
		(pad "85" smd rect
			(at -2.050034 13.17498 90)
			(size 0.519938 1.4986)
			(layers "F.Cu" "F.Mask" "F.Paste")
			(net "GND")
		)
		(pad "86" smd rect
			(at -2.050034 14.025118 90)
			(size 0.519938 1.4986)
			(layers "F.Cu" "F.Mask" "F.Paste")
			(net "M_D_CPU0_SA_RSP<0>")
		)
		(pad "87" smd rect
			(at -2.050034 14.875002 90)
			(size 0.519938 1.4986)
			(layers "F.Cu" "F.Mask" "F.Paste")
			(net "M_D_CPU0_SB_RSP<0>")
		)
		(pad "88" smd rect
			(at -2.050034 15.724886 90)
			(size 0.519938 1.4986)
			(layers "F.Cu" "F.Mask" "F.Paste")
			(net "GND")
		)
		(pad "89" smd rect
			(at -2.050034 16.575024 90)
			(size 0.519938 1.4986)
			(layers "F.Cu" "F.Mask" "F.Paste")
			(net "M_D_CPU0_SB_CB<4>")
		)
		(pad "90" smd rect
			(at -2.050034 17.424908 90)
			(size 0.519938 1.4986)
			(layers "F.Cu" "F.Mask" "F.Paste")
			(net "GND")
		)
		(pad "91" smd rect
			(at -2.050034 18.275046 90)
			(size 0.519938 1.4986)
			(layers "F.Cu" "F.Mask" "F.Paste")
			(net "M_D_CPU0_SB_CB<5>")
		)
		(pad "92" smd rect
			(at -2.050034 19.12493 90)
			(size 0.519938 1.4986)
			(layers "F.Cu" "F.Mask" "F.Paste")
			(net "GND")
		)
	)
)
